# S9S_MB_2U (Grand Teton) — schematic netlist excerpt (pin names and nets, part order shuffled) for the footprints in the layout excerpt that follows; sources: Cadence DE-HDL packaged netlist, KiCad conversion of 03242023_DA0F0TMBIJ0_F0T_Motherboard_J_brd_V01_OCP.brd

H31  HOLE  EMPTY  pkg TH  page 311 : \1\ = GND
R1712  Q_RES  4.7K 5% EMPTY  pkg 0402LF  page 266 : A = SMB_VR_3V3AUX_SDA_R3 ; B = P3V3_AUX
C265  Q_CAP  47UF 4V 20% X6S  pkg C0805  page 77 : A = PVCCIN_CPU1 ; B = GND

(kicad_pcb
	(version 20260206)
	(generator "pcbnew")
	(generator_version "10.0")
	(general
		(thickness 1.6)
		(legacy_teardrops no)
	)
	(paper "A4")
	(title_block
		(title "03242023_DA0F0TMBIJ0_F0T_Motherboard_J_brd_V01_OCP.brd")
		(comment 1 "Grand Teton / footprints 2043-2045 of 6105")
	)
	(layers
		(0 "F.Cu" signal "TOP")
		(4 "In1.Cu" signal "GND")
		(6 "In2.Cu" signal "IN1")
		(8 "In3.Cu" signal "GND1")
		(10 "In4.Cu" signal "IN2")
		(12 "In5.Cu" signal "GND2")
		(14 "In6.Cu" signal "IN3")
		(16 "In7.Cu" signal "GND3")
		(18 "In8.Cu" signal "VCC")
		(20 "In9.Cu" signal "VCC1")
		(22 "In10.Cu" signal "GND4")
		(24 "In11.Cu" signal "IN4")
		(26 "In12.Cu" signal "GND5")
		(28 "In13.Cu" signal "IN5")
		(30 "In14.Cu" signal "GND6")
		(32 "In15.Cu" signal "IN6")
		(34 "In16.Cu" signal "GND7")
		(2 "B.Cu" signal "BOTTOM")
		(9 "F.Adhes" user "F.Adhesive")
		(11 "B.Adhes" user "B.Adhesive")
		(13 "F.Paste" user "Package Geometry/Pastemask Top")
		(15 "B.Paste" user "Package Geometry/Pastemask Bottom")
		(5 "F.SilkS" user "Ref Des/Silkscreen Top")
		(7 "B.SilkS" user "Ref Des/Silkscreen Bottom")
		(1 "F.Mask" user "Board Geometry/Soldermask Top")
		(3 "B.Mask" user "Board Geometry/Soldermask Bottom")
		(17 "Dwgs.User" user "User.Drawings")
		(19 "Cmts.User" user "User.Comments")
		(21 "Eco1.User" user "User.Eco1")
		(23 "Eco2.User" user "User.Eco2")
		(25 "Edge.Cuts" user "Board Geometry/Outline")
		(27 "Margin" user)
		(31 "F.CrtYd" user "Package Geometry/Place Bound Top")
		(29 "B.CrtYd" user "Package Geometry/Place Bound Bottom")
		(35 "F.Fab" user "Ref Des/Assembly Top")
		(33 "B.Fab" user "Ref Des/Assembly Bottom")
	)
	(footprint ""
		(layer "F.Cu")
		(at 141.66088 -368.645948 -90)
		(property "Reference" "R1712"
			(at 0 0 270)
			(layer "F.SilkS")
			(hide yes)
			(effects
				(font
					(size 1.27 1.27)
				)
			)
		)
		(property "Value" ""
			(at 0 0 270)
			(layer "F.Fab")
			(effects
				(font
					(size 1.27 1.27)
				)
			)
		)
		(duplicate_pad_numbers_are_jumpers no)
		(fp_line
			(start -0.7874 0.4064)
			(end -0.7874 -0.4064)
			(stroke
				(width 0.1524)
				(type default)
			)
			(layer "F.SilkS")
		)
		(fp_line
			(start 0.7874 0.4064)
			(end -0.7874 0.4064)
			(stroke
				(width 0.1524)
				(type default)
			)
			(layer "F.SilkS")
		)
		(fp_line
			(start -0.7874 -0.4064)
			(end 0.7874 -0.4064)
			(stroke
				(width 0.1524)
				(type default)
			)
			(layer "F.SilkS")
		)
		(fp_line
			(start 0.7874 -0.4064)
			(end 0.7874 0.4064)
			(stroke
				(width 0.1524)
				(type default)
			)
			(layer "F.SilkS")
		)
		(fp_line
			(start -0.67945 0.3048)
			(end -0.67945 -0.305054)
			(stroke
				(width 0.1)
				(type default)
			)
			(layer "F.Fab")
		)
		(fp_line
			(start -0.12065 0.3048)
			(end -0.67945 0.3048)
			(stroke
				(width 0.1)
				(type default)
			)
			(layer "F.Fab")
		)
		(fp_line
			(start 0.120396 0.3048)
			(end 0.120396 0.2794)
			(stroke
				(width 0.1)
				(type default)
			)
			(layer "F.Fab")
		)
		(fp_line
			(start 0.67945 0.3048)
			(end 0.120396 0.3048)
			(stroke
				(width 0.1)
				(type default)
			)
			(layer "F.Fab")
		)
		(fp_line
			(start -0.12065 0.2794)
			(end -0.12065 0.3048)
			(stroke
				(width 0.1)
				(type default)
			)
			(layer "F.Fab")
		)
		(fp_line
			(start 0.120396 0.2794)
			(end -0.12065 0.2794)
			(stroke
				(width 0.1)
				(type default)
			)
			(layer "F.Fab")
		)
		(fp_line
			(start -0.12065 -0.2794)
			(end 0.12065 -0.2794)
			(stroke
				(width 0.1)
				(type default)
			)
			(layer "F.Fab")
		)
		(fp_line
			(start 0.12065 -0.2794)
			(end 0.12065 -0.3048)
			(stroke
				(width 0.1)
				(type default)
			)
			(layer "F.Fab")
		)
		(fp_line
			(start 0.12065 -0.3048)
			(end 0.67945 -0.3048)
			(stroke
				(width 0.1)
				(type default)
			)
			(layer "F.Fab")
		)
		(fp_line
			(start 0.67945 -0.3048)
			(end 0.67945 0.3048)
			(stroke
				(width 0.1)
				(type default)
			)
			(layer "F.Fab")
		)
		(fp_line
			(start -0.67945 -0.305054)
			(end -0.12065 -0.305054)
			(stroke
				(width 0.1)
				(type default)
			)
			(layer "F.Fab")
		)
		(fp_line
			(start -0.12065 -0.305054)
			(end -0.12065 -0.2794)
			(stroke
				(width 0.1)
				(type default)
			)
			(layer "F.Fab")
		)
		(pad "1" smd circle
			(at -0.40005 0 270)
			(size 0 0)
			(layers "F.Cu" "F.Mask" "F.Paste")
			(net "SMB_VR_3V3AUX_SDA_R3")
		)
		(pad "2" smd circle
			(at 0.40005 0 270)
			(size 0 0)
			(layers "F.Cu" "F.Mask" "F.Paste")
			(net "P3V3_AUX")
		)
	)
	(footprint ""
		(layer "F.Cu")
		(at 108.56722 -294.01008)
		(property "Reference" "C265"
			(at 0 0 0)
			(layer "F.SilkS")
			(hide yes)
			(effects
				(font
					(size 1.27 1.27)
				)
			)
		)
		(property "Value" ""
			(at 0 0 0)
			(layer "F.Fab")
			(effects
				(font
					(size 1.27 1.27)
				)
			)
		)
		(duplicate_pad_numbers_are_jumpers no)
		(fp_line
			(start -1.524 -0.762)
			(end 1.524 -0.762)
			(stroke
				(width 0.1524)
				(type default)
			)
			(layer "F.SilkS")
		)
		(fp_line
			(start -1.524 0.762)
			(end -1.524 -0.762)
			(stroke
				(width 0.1524)
				(type default)
			)
			(layer "F.SilkS")
		)
		(fp_line
			(start 1.524 -0.762)
			(end 1.524 0.762)
			(stroke
				(width 0.1524)
				(type default)
			)
			(layer "F.SilkS")
		)
		(fp_line
			(start 1.524 0.762)
			(end -1.524 0.762)
			(stroke
				(width 0.1524)
				(type default)
			)
			(layer "F.SilkS")
		)
		(fp_line
			(start -1.1049 -0.724916)
			(end -1.1049 0.724916)
			(stroke
				(width 0.1)
				(type default)
			)
			(layer "F.Fab")
		)
		(fp_line
			(start -1.1049 0.724916)
			(end 1.1049 0.724916)
			(stroke
				(width 0.1)
				(type default)
			)
			(layer "F.Fab")
		)
		(fp_line
			(start 1.1049 -0.724916)
			(end -1.1049 -0.724916)
			(stroke
				(width 0.1)
				(type default)
			)
			(layer "F.Fab")
		)
		(fp_line
			(start 1.1049 0.724916)
			(end 1.1049 -0.724916)
			(stroke
				(width 0.1)
				(type default)
			)
			(layer "F.Fab")
		)
		(pad "1" smd rect
			(at -0.889 0 180)
			(size 1.016 1.27)
			(layers "F.Cu" "F.Mask" "F.Paste")
			(net "PVCCIN_CPU1")
		)
		(pad "2" smd rect
			(at 0.889 0 180)
			(size 1.016 1.27)
			(layers "F.Cu" "F.Mask" "F.Paste")
			(net "GND")
		)
	)
	(footprint ""
		(layer "F.Cu")
		(at 70.382892 -47.049944)
		(property "Reference" "H31"
			(at -1.7272 -4.511548 0)
			(unlocked yes)
			(layer "B.SilkS")
			(effects
				(font
					(size 0.7874 0.5842)
					(thickness 0.1524)
				)
				(justify left mirror)
			)
		)
		(property "Value" ""
			(at 0 0 0)
			(layer "F.Fab")
			(effects
				(font
					(size 1.27 1.27)
				)
			)
		)
		(duplicate_pad_numbers_are_jumpers no)
		(pad "1" thru_hole circle
			(at 0 0)
			(size 4.5212 4.5212)
			(drill 3.81)
			(layers "*.Cu" "*.Mask")
			(remove_unused_layers no)
			(net "GND")
			(clearance -0.1016)
			(padstack
				(mode front_inner_back)
				(layer "Inner"
					(shape circle)
					(size 5.6134 5.6134)
					(clearance -0.6477)
				)
				(layer "B.Cu"
					(shape circle)
					(size 8.001 8.001)
					(clearance -1.8415)
				)
			)
		)
	)
)
